FILE_TYPE = CONNECTIVITY;
{Allegro Design Entry HDL 17.4-2019 S026 (4007227) 1/17/2022}
"PAGE_NUMBER" = 456;
0"NC";
END.
